# S9S_MB_2U (Grand Teton) — schematic netlist excerpt (pin names and nets, part order shuffled) for the footprints in the layout excerpt that follows; sources: Cadence DE-HDL packaged netlist, KiCad conversion of 03242023_DA0F0TMBIJ0_F0T_Motherboard_J_brd_V01_OCP.brd

R3525  Q_RES  54.9K 1% CHIP  pkg 0402LF  page 147 : A = P3V3_AUX ; B = GPU_FPGA_EROT_FATALERR_N
D78  Q_LED  IC  pkg SMLF  page 253 : A = LED_PWRGD_PVNN_MAIN_CPU0 ; C = LED_PWRGD_PVNN_MAIN_CPU0_D

(kicad_pcb
	(version 20260206)
	(generator "pcbnew")
	(generator_version "10.0")
	(general
		(thickness 1.6)
		(legacy_teardrops no)
	)
	(paper "A4")
	(title_block
		(title "03242023_DA0F0TMBIJ0_F0T_Motherboard_J_brd_V01_OCP.brd")
		(comment 1 "Grand Teton / footprints 2885-2886 of 6105")
	)
	(layers
		(0 "F.Cu" signal "TOP")
		(4 "In1.Cu" signal "GND")
		(6 "In2.Cu" signal "IN1")
		(8 "In3.Cu" signal "GND1")
		(10 "In4.Cu" signal "IN2")
		(12 "In5.Cu" signal "GND2")
		(14 "In6.Cu" signal "IN3")
		(16 "In7.Cu" signal "GND3")
		(18 "In8.Cu" signal "VCC")
		(20 "In9.Cu" signal "VCC1")
		(22 "In10.Cu" signal "GND4")
		(24 "In11.Cu" signal "IN4")
		(26 "In12.Cu" signal "GND5")
		(28 "In13.Cu" signal "IN5")
		(30 "In14.Cu" signal "GND6")
		(32 "In15.Cu" signal "IN6")
		(34 "In16.Cu" signal "GND7")
		(2 "B.Cu" signal "BOTTOM")
		(9 "F.Adhes" user "F.Adhesive")
		(11 "B.Adhes" user "B.Adhesive")
		(13 "F.Paste" user "Package Geometry/Pastemask Top")
		(15 "B.Paste" user "Package Geometry/Pastemask Bottom")
		(5 "F.SilkS" user "Ref Des/Silkscreen Top")
		(7 "B.SilkS" user "Ref Des/Silkscreen Bottom")
		(1 "F.Mask" user "Board Geometry/Soldermask Top")
		(3 "B.Mask" user "Board Geometry/Soldermask Bottom")
		(17 "Dwgs.User" user "User.Drawings")
		(19 "Cmts.User" user "User.Comments")
		(21 "Eco1.User" user "User.Eco1")
		(23 "Eco2.User" user "User.Eco2")
		(25 "Edge.Cuts" user "Board Geometry/Outline")
		(27 "Margin" user)
		(31 "F.CrtYd" user "Package Geometry/Place Bound Top")
		(29 "B.CrtYd" user "Package Geometry/Place Bound Bottom")
		(35 "F.Fab" user "Ref Des/Assembly Top")
		(33 "B.Fab" user "Ref Des/Assembly Bottom")
	)
	(footprint ""
		(layer "F.Cu")
		(at 96.141286 -427.776386 -90)
		(property "Reference" "R3525"
			(at 0 0 270)
			(layer "F.SilkS")
			(hide yes)
			(effects
				(font
					(size 1.27 1.27)
				)
			)
		)
		(property "Value" ""
			(at 0 0 270)
			(layer "F.Fab")
			(effects
				(font
					(size 1.27 1.27)
				)
			)
		)
		(duplicate_pad_numbers_are_jumpers no)
		(fp_line
			(start -0.7874 0.4064)
			(end -0.7874 -0.4064)
			(stroke
				(width 0.1524)
				(type default)
			)
			(layer "F.SilkS")
		)
		(fp_line
			(start 0.7874 0.4064)
			(end -0.7874 0.4064)
			(stroke
				(width 0.1524)
				(type default)
			)
			(layer "F.SilkS")
		)
		(fp_line
			(start -0.7874 -0.4064)
			(end 0.7874 -0.4064)
			(stroke
				(width 0.1524)
				(type default)
			)
			(layer "F.SilkS")
		)
		(fp_line
			(start 0.7874 -0.4064)
			(end 0.7874 0.4064)
			(stroke
				(width 0.1524)
				(type default)
			)
			(layer "F.SilkS")
		)
		(fp_line
			(start -0.67945 0.3048)
			(end -0.67945 -0.305054)
			(stroke
				(width 0.1)
				(type default)
			)
			(layer "F.Fab")
		)
		(fp_line
			(start -0.12065 0.3048)
			(end -0.67945 0.3048)
			(stroke
				(width 0.1)
				(type default)
			)
			(layer "F.Fab")
		)
		(fp_line
			(start 0.120396 0.3048)
			(end 0.120396 0.2794)
			(stroke
				(width 0.1)
				(type default)
			)
			(layer "F.Fab")
		)
		(fp_line
			(start 0.67945 0.3048)
			(end 0.120396 0.3048)
			(stroke
				(width 0.1)
				(type default)
			)
			(layer "F.Fab")
		)
		(fp_line
			(start -0.12065 0.2794)
			(end -0.12065 0.3048)
			(stroke
				(width 0.1)
				(type default)
			)
			(layer "F.Fab")
		)
		(fp_line
			(start 0.120396 0.2794)
			(end -0.12065 0.2794)
			(stroke
				(width 0.1)
				(type default)
			)
			(layer "F.Fab")
		)
		(fp_line
			(start -0.12065 -0.2794)
			(end 0.12065 -0.2794)
			(stroke
				(width 0.1)
				(type default)
			)
			(layer "F.Fab")
		)
		(fp_line
			(start 0.12065 -0.2794)
			(end 0.12065 -0.3048)
			(stroke
				(width 0.1)
				(type default)
			)
			(layer "F.Fab")
		)
		(fp_line
			(start 0.12065 -0.3048)
			(end 0.67945 -0.3048)
			(stroke
				(width 0.1)
				(type default)
			)
			(layer "F.Fab")
		)
		(fp_line
			(start 0.67945 -0.3048)
			(end 0.67945 0.3048)
			(stroke
				(width 0.1)
				(type default)
			)
			(layer "F.Fab")
		)
		(fp_line
			(start -0.67945 -0.305054)
			(end -0.12065 -0.305054)
			(stroke
				(width 0.1)
				(type default)
			)
			(layer "F.Fab")
		)
		(fp_line
			(start -0.12065 -0.305054)
			(end -0.12065 -0.2794)
			(stroke
				(width 0.1)
				(type default)
			)
			(layer "F.Fab")
		)
		(pad "1" smd circle
			(at -0.40005 0 270)
			(size 0 0)
			(layers "F.Cu" "F.Mask" "F.Paste")
			(net "P3V3_AUX")
		)
		(pad "2" smd circle
			(at 0.40005 0 270)
			(size 0 0)
			(layers "F.Cu" "F.Mask" "F.Paste")
			(net "GPU_FPGA_EROT_FATALERR_N")
		)
	)
	(footprint ""
		(layer "F.Cu")
		(at 106.584496 -70.78599)
		(property "Reference" "D78"
			(at -53.121306 50.178462 90)
			(unlocked yes)
			(layer "F.SilkS")
			(effects
				(font
					(size 0.635 0.4064)
					(thickness 0.1524)
				)
				(justify left)
			)
		)
		(property "Value" ""
			(at 0 0 0)
			(layer "F.Fab")
			(effects
				(font
					(size 1.27 1.27)
				)
			)
		)
		(duplicate_pad_numbers_are_jumpers no)
		(fp_line
			(start -0.90678 0.4826)
			(end -0.90678 -0.4699)
			(stroke
				(width 0.1524)
				(type default)
			)
			(layer "F.SilkS")
		)
		(fp_line
			(start -0.89408 -0.4826)
			(end 0.90678 -0.4826)
			(stroke
				(width 0.1524)
				(type default)
			)
			(layer "F.SilkS")
		)
		(fp_line
			(start -0.79248 -0.4826)
			(end 1.03378 -0.4826)
			(stroke
				(width 0.1524)
				(type default)
			)
			(layer "F.SilkS")
		)
		(fp_line
			(start -0.64008 -0.4826)
			(end 1.16078 -0.4826)
			(stroke
				(width 0.1524)
				(type default)
			)
			(layer "F.SilkS")
		)
		(fp_line
			(start 0.90678 -0.4826)
			(end 0.90678 0.4826)
			(stroke
				(width 0.1524)
				(type default)
			)
			(layer "F.SilkS")
		)
		(fp_line
			(start 0.90678 0.4826)
			(end -0.90678 0.4826)
			(stroke
				(width 0.1524)
				(type default)
			)
			(layer "F.SilkS")
		)
		(fp_line
			(start 1.03378 -0.4826)
			(end 1.03378 0.4826)
			(stroke
				(width 0.1524)
				(type default)
			)
			(layer "F.SilkS")
		)
		(fp_line
			(start 1.03378 0.4826)
			(end -0.79248 0.4826)
			(stroke
				(width 0.1524)
				(type default)
			)
			(layer "F.SilkS")
		)
		(fp_line
			(start 1.16078 -0.4826)
			(end 1.16078 0.4826)
			(stroke
				(width 0.1524)
				(type default)
			)
			(layer "F.SilkS")
		)
		(fp_line
			(start 1.16078 0.4826)
			(end -0.64008 0.4826)
			(stroke
				(width 0.1524)
				(type default)
			)
			(layer "F.SilkS")
		)
		(fp_line
			(start -0.499872 -0.249936)
			(end 0.499872 -0.249936)
			(stroke
				(width 0.1)
				(type default)
			)
			(layer "F.Fab")
		)
		(fp_line
			(start -0.499872 0.249936)
			(end -0.499872 -0.249936)
			(stroke
				(width 0.1)
				(type default)
			)
			(layer "F.Fab")
		)
		(fp_line
			(start 0.499872 -0.249936)
			(end 0.499872 0.249936)
			(stroke
				(width 0.1)
				(type default)
			)
			(layer "F.Fab")
		)
		(fp_line
			(start 0.499872 0.249936)
			(end -0.499872 0.249936)
			(stroke
				(width 0.1)
				(type default)
			)
			(layer "F.Fab")
		)
		(pad "A" smd rect
			(at -0.47498 0)
			(size 0.6096 0.7112)
			(layers "F.Cu" "F.Mask" "F.Paste")
			(net "LED_PWRGD_PVNN_MAIN_CPU0")
		)
		(pad "C" smd rect
			(at 0.47498 0)
			(size 0.6096 0.7112)
			(layers "F.Cu" "F.Mask" "F.Paste")
			(net "LED_PWRGD_PVNN_MAIN_CPU0_D")
		)
	)
)
